# T6G (Grand Teton) — schematic netlist excerpt (pin names and nets, part order shuffled) for the footprints in the layout excerpt that follows; sources: Cadence DE-HDL packaged netlist, KiCad conversion of 04192023_DAF0TMB3IC0_F0TG_MB_C_brd_V02_OCP.brd

R6265  Q_RES  0 5% CHIP  pkg 0402LF  page 179 : A = USB_HUB2_TI_VDD_MRP_USB3DN_TXDP3 ; B = P1V2_CPU0_USB2_DVDD12
PC1845  Q_CAPP  220UF 6.3V 20% ALUM  pkg SMLF  page 189 : A = P5V_AUX ; B = GND

(kicad_pcb
	(version 20260206)
	(generator "pcbnew")
	(generator_version "10.0")
	(general
		(thickness 1.6)
		(legacy_teardrops no)
	)
	(paper "A4")
	(title_block
		(title "04192023_DAF0TMB3IC0_F0TG_MB_C_brd_V02_OCP.brd")
		(comment 1 "Grand Teton / footprints 4558-4559 of 8354")
	)
	(layers
		(0 "F.Cu" signal "TOP")
		(4 "In1.Cu" signal "GND")
		(6 "In2.Cu" signal "IN1")
		(8 "In3.Cu" signal "GND1")
		(10 "In4.Cu" signal "IN2")
		(12 "In5.Cu" signal "GND2")
		(14 "In6.Cu" signal "IN3")
		(16 "In7.Cu" signal "GND3")
		(18 "In8.Cu" signal "VCC")
		(20 "In9.Cu" signal "VCC1")
		(22 "In10.Cu" signal "GND4")
		(24 "In11.Cu" signal "IN4")
		(26 "In12.Cu" signal "GND5")
		(28 "In13.Cu" signal "IN5")
		(30 "In14.Cu" signal "GND6")
		(32 "In15.Cu" signal "IN6")
		(34 "In16.Cu" signal "GND7")
		(2 "B.Cu" signal "BOTTOM")
		(9 "F.Adhes" user "F.Adhesive")
		(11 "B.Adhes" user "B.Adhesive")
		(13 "F.Paste" user "Package Geometry/Pastemask Top")
		(15 "B.Paste" user "Package Geometry/Pastemask Bottom")
		(5 "F.SilkS" user "Ref Des/Silkscreen Top")
		(7 "B.SilkS" user "Ref Des/Silkscreen Bottom")
		(1 "F.Mask" user "Board Geometry/Soldermask Top")
		(3 "B.Mask" user "Board Geometry/Soldermask Bottom")
		(17 "Dwgs.User" user "User.Drawings")
		(19 "Cmts.User" user "User.Comments")
		(21 "Eco1.User" user "User.Eco1")
		(23 "Eco2.User" user "User.Eco2")
		(25 "Edge.Cuts" user "Board Geometry/Outline")
		(27 "Margin" user)
		(31 "F.CrtYd" user "Package Geometry/Place Bound Top")
		(29 "B.CrtYd" user "Package Geometry/Place Bound Bottom")
		(35 "F.Fab" user "Ref Des/Assembly Top")
		(33 "B.Fab" user "Ref Des/Assembly Bottom")
	)
	(footprint ""
		(layer "F.Cu")
		(at 422.74617 -153.594562)
		(property "Reference" "PC1845"
			(at -1.86817 3.761232 0)
			(unlocked yes)
			(layer "F.SilkS")
			(effects
				(font
					(size 0.7874 0.5842)
					(thickness 0.1524)
				)
				(justify left)
			)
		)
		(property "Value" ""
			(at 0 0 0)
			(layer "F.Fab")
			(effects
				(font
					(size 1.27 1.27)
				)
			)
		)
		(duplicate_pad_numbers_are_jumpers no)
		(fp_line
			(start -2.750058 -1.988058)
			(end -2.750058 -0.9398)
			(stroke
				(width 0.1524)
				(type default)
			)
			(layer "F.SilkS")
		)
		(fp_line
			(start -2.750058 0.9398)
			(end -2.750058 1.988058)
			(stroke
				(width 0.1524)
				(type default)
			)
			(layer "F.SilkS")
		)
		(fp_line
			(start -2.750058 1.988058)
			(end -1.988058 2.750058)
			(stroke
				(width 0.1524)
				(type default)
			)
			(layer "F.SilkS")
		)
		(fp_line
			(start -1.988058 -2.750058)
			(end -2.750058 -1.988058)
			(stroke
				(width 0.1524)
				(type default)
			)
			(layer "F.SilkS")
		)
		(fp_line
			(start -1.988058 2.750058)
			(end 2.750058 2.750058)
			(stroke
				(width 0.1524)
				(type default)
			)
			(layer "F.SilkS")
		)
		(fp_line
			(start 2.750058 -2.750058)
			(end -1.988058 -2.750058)
			(stroke
				(width 0.1524)
				(type default)
			)
			(layer "F.SilkS")
		)
		(fp_line
			(start 2.750058 -0.9398)
			(end 2.750058 -2.750058)
			(stroke
				(width 0.1524)
				(type default)
			)
			(layer "F.SilkS")
		)
		(fp_line
			(start 2.750058 2.750058)
			(end 2.750058 0.9398)
			(stroke
				(width 0.1524)
				(type default)
			)
			(layer "F.SilkS")
		)
		(fp_line
			(start -2.750058 -2.750058)
			(end -2.750058 2.750058)
			(stroke
				(width 0.1)
				(type default)
			)
			(layer "F.Fab")
		)
		(fp_line
			(start -2.750058 2.750058)
			(end 2.750058 2.750058)
			(stroke
				(width 0.1)
				(type default)
			)
			(layer "F.Fab")
		)
		(fp_line
			(start 2.750058 -2.750058)
			(end -2.750058 -2.750058)
			(stroke
				(width 0.1)
				(type default)
			)
			(layer "F.Fab")
		)
		(fp_line
			(start 2.750058 2.750058)
			(end 2.750058 -2.750058)
			(stroke
				(width 0.1)
				(type default)
			)
			(layer "F.Fab")
		)
		(pad "1" smd rect
			(at -2.199894 0 90)
			(size 1.6002 3.0226)
			(layers "F.Cu" "F.Mask" "F.Paste")
			(net "P5V_AUX")
		)
		(pad "2" smd rect
			(at 2.199894 0 90)
			(size 1.6002 3.0226)
			(layers "F.Cu" "F.Mask" "F.Paste")
			(net "GND")
		)
	)
	(footprint ""
		(layer "F.Cu")
		(at 120.68175 -26.815796)
		(property "Reference" "R6265"
			(at 0 0 0)
			(layer "F.SilkS")
			(hide yes)
			(effects
				(font
					(size 1.27 1.27)
				)
			)
		)
		(property "Value" ""
			(at 0 0 0)
			(layer "F.Fab")
			(effects
				(font
					(size 1.27 1.27)
				)
			)
		)
		(duplicate_pad_numbers_are_jumpers no)
		(fp_line
			(start -0.7874 -0.4064)
			(end 0.7874 -0.4064)
			(stroke
				(width 0.1524)
				(type default)
			)
			(layer "F.SilkS")
		)
		(fp_line
			(start -0.7874 0.4064)
			(end -0.7874 -0.4064)
			(stroke
				(width 0.1524)
				(type default)
			)
			(layer "F.SilkS")
		)
		(fp_line
			(start 0.7874 -0.4064)
			(end 0.7874 0.4064)
			(stroke
				(width 0.1524)
				(type default)
			)
			(layer "F.SilkS")
		)
		(fp_line
			(start 0.7874 0.4064)
			(end -0.7874 0.4064)
			(stroke
				(width 0.1524)
				(type default)
			)
			(layer "F.SilkS")
		)
		(fp_line
			(start -0.67945 -0.305054)
			(end -0.12065 -0.305054)
			(stroke
				(width 0.1)
				(type default)
			)
			(layer "F.Fab")
		)
		(fp_line
			(start -0.67945 0.3048)
			(end -0.67945 -0.305054)
			(stroke
				(width 0.1)
				(type default)
			)
			(layer "F.Fab")
		)
		(fp_line
			(start -0.12065 -0.305054)
			(end -0.12065 -0.2794)
			(stroke
				(width 0.1)
				(type default)
			)
			(layer "F.Fab")
		)
		(fp_line
			(start -0.12065 -0.2794)
			(end 0.12065 -0.2794)
			(stroke
				(width 0.1)
				(type default)
			)
			(layer "F.Fab")
		)
		(fp_line
			(start -0.12065 0.2794)
			(end -0.12065 0.3048)
			(stroke
				(width 0.1)
				(type default)
			)
			(layer "F.Fab")
		)
		(fp_line
			(start -0.12065 0.3048)
			(end -0.67945 0.3048)
			(stroke
				(width 0.1)
				(type default)
			)
			(layer "F.Fab")
		)
		(fp_line
			(start 0.120396 0.2794)
			(end -0.12065 0.2794)
			(stroke
				(width 0.1)
				(type default)
			)
			(layer "F.Fab")
		)
		(fp_line
			(start 0.120396 0.3048)
			(end 0.120396 0.2794)
			(stroke
				(width 0.1)
				(type default)
			)
			(layer "F.Fab")
		)
		(fp_line
			(start 0.12065 -0.3048)
			(end 0.67945 -0.3048)
			(stroke
				(width 0.1)
				(type default)
			)
			(layer "F.Fab")
		)
		(fp_line
			(start 0.12065 -0.2794)
			(end 0.12065 -0.3048)
			(stroke
				(width 0.1)
				(type default)
			)
			(layer "F.Fab")
		)
		(fp_line
			(start 0.67945 -0.3048)
			(end 0.67945 0.3048)
			(stroke
				(width 0.1)
				(type default)
			)
			(layer "F.Fab")
		)
		(fp_line
			(start 0.67945 0.3048)
			(end 0.120396 0.3048)
			(stroke
				(width 0.1)
				(type default)
			)
			(layer "F.Fab")
		)
		(pad "1" smd circle
			(at -0.40005 0)
			(size 0 0)
			(layers "F.Cu" "F.Mask" "F.Paste")
			(net "USB_HUB2_TI_VDD_MRP_USB3DN_TXDP3")
		)
		(pad "2" smd circle
			(at 0.40005 0)
			(size 0 0)
			(layers "F.Cu" "F.Mask" "F.Paste")
			(net "P1V2_CPU0_USB2_DVDD12")
		)
	)
)
